# S9S_MB_2U (Grand Teton) — schematic netlist excerpt (pin names and nets, part order shuffled) for the footprints in the layout excerpt that follows; sources: Cadence DE-HDL packaged netlist, KiCad conversion of 03242023_DA0F0TMBIJ0_F0T_Motherboard_J_brd_V01_OCP.brd

PC642  Q_CAP  22UF 4V 20% X6S  pkg C0805  page 279 : A = PVCCD_HV_CPU0 ; B = GND
R1445  Q_RES  2K 1% CHIP  pkg 0402LF  page 282 : A = FM_PVNN_MAIN_CPU0_EN ; B = GND
PC1679  Q_CAP  22UF 16V 20% X6S  pkg C0805  page 289 : A = SW_P12V_PVCCFA_EHV_FIVRA_CPU1_L ; B = GND

(kicad_pcb
	(version 20260206)
	(generator "pcbnew")
	(generator_version "10.0")
	(general
		(thickness 1.6)
		(legacy_teardrops no)
	)
	(paper "A4")
	(title_block
		(title "03242023_DA0F0TMBIJ0_F0T_Motherboard_J_brd_V01_OCP.brd")
		(comment 1 "Grand Teton / footprints 4660-4662 of 6105")
	)
	(layers
		(0 "F.Cu" signal "TOP")
		(4 "In1.Cu" signal "GND")
		(6 "In2.Cu" signal "IN1")
		(8 "In3.Cu" signal "GND1")
		(10 "In4.Cu" signal "IN2")
		(12 "In5.Cu" signal "GND2")
		(14 "In6.Cu" signal "IN3")
		(16 "In7.Cu" signal "GND3")
		(18 "In8.Cu" signal "VCC")
		(20 "In9.Cu" signal "VCC1")
		(22 "In10.Cu" signal "GND4")
		(24 "In11.Cu" signal "IN4")
		(26 "In12.Cu" signal "GND5")
		(28 "In13.Cu" signal "IN5")
		(30 "In14.Cu" signal "GND6")
		(32 "In15.Cu" signal "IN6")
		(34 "In16.Cu" signal "GND7")
		(2 "B.Cu" signal "BOTTOM")
		(9 "F.Adhes" user "F.Adhesive")
		(11 "B.Adhes" user "B.Adhesive")
		(13 "F.Paste" user "Package Geometry/Pastemask Top")
		(15 "B.Paste" user "Package Geometry/Pastemask Bottom")
		(5 "F.SilkS" user "Ref Des/Silkscreen Top")
		(7 "B.SilkS" user "Ref Des/Silkscreen Bottom")
		(1 "F.Mask" user "Board Geometry/Soldermask Top")
		(3 "B.Mask" user "Board Geometry/Soldermask Bottom")
		(17 "Dwgs.User" user "User.Drawings")
		(19 "Cmts.User" user "User.Comments")
		(21 "Eco1.User" user "User.Eco1")
		(23 "Eco2.User" user "User.Eco2")
		(25 "Edge.Cuts" user "Board Geometry/Outline")
		(27 "Margin" user)
		(31 "F.CrtYd" user "Package Geometry/Place Bound Top")
		(29 "B.CrtYd" user "Package Geometry/Place Bound Bottom")
		(35 "F.Fab" user "Ref Des/Assembly Top")
		(33 "B.Fab" user "Ref Des/Assembly Bottom")
	)
	(footprint ""
		(layer "B.Cu")
		(at 45.857922 -357.91521 180)
		(property "Reference" "PC1679"
			(at 0 0 0)
			(layer "B.SilkS")
			(hide yes)
			(effects
				(font
					(size 1.27 1.27)
				)
				(justify mirror)
			)
		)
		(property "Value" ""
			(at 0 0 0)
			(layer "B.Fab")
			(effects
				(font
					(size 1.27 1.27)
				)
				(justify mirror)
			)
		)
		(duplicate_pad_numbers_are_jumpers no)
		(fp_line
			(start 1.524 0.762)
			(end 1.524 -0.762)
			(stroke
				(width 0.1524)
				(type default)
			)
			(layer "B.SilkS")
		)
		(fp_line
			(start 1.524 -0.762)
			(end -1.524 -0.762)
			(stroke
				(width 0.1524)
				(type default)
			)
			(layer "B.SilkS")
		)
		(fp_line
			(start -1.524 0.762)
			(end 1.524 0.762)
			(stroke
				(width 0.1524)
				(type default)
			)
			(layer "B.SilkS")
		)
		(fp_line
			(start -1.524 -0.762)
			(end -1.524 0.762)
			(stroke
				(width 0.1524)
				(type default)
			)
			(layer "B.SilkS")
		)
		(fp_line
			(start 1.1049 0.724916)
			(end -1.1049 0.724916)
			(stroke
				(width 0.1)
				(type default)
			)
			(layer "B.Fab")
		)
		(fp_line
			(start 1.1049 -0.724916)
			(end 1.1049 0.724916)
			(stroke
				(width 0.1)
				(type default)
			)
			(layer "B.Fab")
		)
		(fp_line
			(start -1.1049 0.724916)
			(end -1.1049 -0.724916)
			(stroke
				(width 0.1)
				(type default)
			)
			(layer "B.Fab")
		)
		(fp_line
			(start -1.1049 -0.724916)
			(end 1.1049 -0.724916)
			(stroke
				(width 0.1)
				(type default)
			)
			(layer "B.Fab")
		)
		(pad "1" smd rect
			(at 0.889 0 180)
			(size 1.016 1.27)
			(layers "B.Cu" "B.Mask" "B.Paste")
			(net "SW_P12V_PVCCFA_EHV_FIVRA_CPU1_L")
		)
		(pad "2" smd rect
			(at -0.889 0 180)
			(size 1.016 1.27)
			(layers "B.Cu" "B.Mask" "B.Paste")
			(net "GND")
		)
	)
	(footprint ""
		(layer "B.Cu")
		(at 432.325018 -177.15611 90)
		(property "Reference" "R1445"
			(at 0 0 90)
			(layer "B.SilkS")
			(hide yes)
			(effects
				(font
					(size 1.27 1.27)
				)
				(justify mirror)
			)
		)
		(property "Value" ""
			(at 0 0 90)
			(layer "B.Fab")
			(effects
				(font
					(size 1.27 1.27)
				)
				(justify mirror)
			)
		)
		(duplicate_pad_numbers_are_jumpers no)
		(fp_line
			(start 0.7874 -0.4064)
			(end -0.7874 -0.4064)
			(stroke
				(width 0.1524)
				(type default)
			)
			(layer "B.SilkS")
		)
		(fp_line
			(start -0.7874 -0.4064)
			(end -0.7874 0.4064)
			(stroke
				(width 0.1524)
				(type default)
			)
			(layer "B.SilkS")
		)
		(fp_line
			(start 0.7874 0.4064)
			(end 0.7874 -0.4064)
			(stroke
				(width 0.1524)
				(type default)
			)
			(layer "B.SilkS")
		)
		(fp_line
			(start -0.7874 0.4064)
			(end 0.7874 0.4064)
			(stroke
				(width 0.1524)
				(type default)
			)
			(layer "B.SilkS")
		)
		(fp_line
			(start 0.67945 -0.305054)
			(end 0.12065 -0.305054)
			(stroke
				(width 0.1)
				(type default)
			)
			(layer "B.Fab")
		)
		(fp_line
			(start 0.12065 -0.305054)
			(end 0.12065 -0.2794)
			(stroke
				(width 0.1)
				(type default)
			)
			(layer "B.Fab")
		)
		(fp_line
			(start -0.12065 -0.3048)
			(end -0.67945 -0.3048)
			(stroke
				(width 0.1)
				(type default)
			)
			(layer "B.Fab")
		)
		(fp_line
			(start -0.67945 -0.3048)
			(end -0.67945 0.3048)
			(stroke
				(width 0.1)
				(type default)
			)
			(layer "B.Fab")
		)
		(fp_line
			(start 0.12065 -0.2794)
			(end -0.12065 -0.2794)
			(stroke
				(width 0.1)
				(type default)
			)
			(layer "B.Fab")
		)
		(fp_line
			(start -0.12065 -0.2794)
			(end -0.12065 -0.3048)
			(stroke
				(width 0.1)
				(type default)
			)
			(layer "B.Fab")
		)
		(fp_line
			(start 0.12065 0.2794)
			(end 0.12065 0.3048)
			(stroke
				(width 0.1)
				(type default)
			)
			(layer "B.Fab")
		)
		(fp_line
			(start -0.120396 0.2794)
			(end 0.12065 0.2794)
			(stroke
				(width 0.1)
				(type default)
			)
			(layer "B.Fab")
		)
		(fp_line
			(start 0.67945 0.3048)
			(end 0.67945 -0.305054)
			(stroke
				(width 0.1)
				(type default)
			)
			(layer "B.Fab")
		)
		(fp_line
			(start 0.12065 0.3048)
			(end 0.67945 0.3048)
			(stroke
				(width 0.1)
				(type default)
			)
			(layer "B.Fab")
		)
		(fp_line
			(start -0.120396 0.3048)
			(end -0.120396 0.2794)
			(stroke
				(width 0.1)
				(type default)
			)
			(layer "B.Fab")
		)
		(fp_line
			(start -0.67945 0.3048)
			(end -0.120396 0.3048)
			(stroke
				(width 0.1)
				(type default)
			)
			(layer "B.Fab")
		)
		(pad "1" smd circle
			(at 0.40005 0 270)
			(size 0 0)
			(layers "B.Cu" "B.Mask" "B.Paste")
			(net "FM_PVNN_MAIN_CPU0_EN")
		)
		(pad "2" smd circle
			(at -0.40005 0 270)
			(size 0 0)
			(layers "B.Cu" "B.Mask" "B.Paste")
			(net "GND")
		)
	)
	(footprint ""
		(layer "B.Cu")
		(at 407.91257 -165.504368 180)
		(property "Reference" "PC642"
			(at 0 0 0)
			(layer "B.SilkS")
			(hide yes)
			(effects
				(font
					(size 1.27 1.27)
				)
				(justify mirror)
			)
		)
		(property "Value" ""
			(at 0 0 0)
			(layer "B.Fab")
			(effects
				(font
					(size 1.27 1.27)
				)
				(justify mirror)
			)
		)
		(duplicate_pad_numbers_are_jumpers no)
		(fp_line
			(start 1.524 0.762)
			(end 1.524 -0.762)
			(stroke
				(width 0.1524)
				(type default)
			)
			(layer "B.SilkS")
		)
		(fp_line
			(start 1.524 -0.762)
			(end -1.524 -0.762)
			(stroke
				(width 0.1524)
				(type default)
			)
			(layer "B.SilkS")
		)
		(fp_line
			(start -1.524 0.762)
			(end 1.524 0.762)
			(stroke
				(width 0.1524)
				(type default)
			)
			(layer "B.SilkS")
		)
		(fp_line
			(start -1.524 -0.762)
			(end -1.524 0.762)
			(stroke
				(width 0.1524)
				(type default)
			)
			(layer "B.SilkS")
		)
		(fp_line
			(start 1.1049 0.724916)
			(end -1.1049 0.724916)
			(stroke
				(width 0.1)
				(type default)
			)
			(layer "B.Fab")
		)
		(fp_line
			(start 1.1049 -0.724916)
			(end 1.1049 0.724916)
			(stroke
				(width 0.1)
				(type default)
			)
			(layer "B.Fab")
		)
		(fp_line
			(start -1.1049 0.724916)
			(end -1.1049 -0.724916)
			(stroke
				(width 0.1)
				(type default)
			)
			(layer "B.Fab")
		)
		(fp_line
			(start -1.1049 -0.724916)
			(end 1.1049 -0.724916)
			(stroke
				(width 0.1)
				(type default)
			)
			(layer "B.Fab")
		)
		(pad "1" smd rect
			(at 0.889 0 180)
			(size 1.016 1.27)
			(layers "B.Cu" "B.Mask" "B.Paste")
			(net "PVCCD_HV_CPU0")
		)
		(pad "2" smd rect
			(at -0.889 0 180)
			(size 1.016 1.27)
			(layers "B.Cu" "B.Mask" "B.Paste")
			(net "GND")
		)
	)
)
